(kicad_pcb
	(version 20241229)
	(generator "pcbnew")
	(generator_version "9.0")
	(general
		(thickness 1.599998)
		(legacy_teardrops no)
	)
	(paper "A4")
	(title_block
		(date "2023-02-12")
		(rev "1.1.5")
		(comment 9 "footprints 322-326 of 473")
	)
	(layers
		(0 "F.Cu" signal)
		(4 "In1.Cu" power "In1.GND")
		(6 "In2.Cu" signal)
		(8 "In3.Cu" power "In3.GND")
		(10 "In4.Cu" power "In4.VCC")
		(12 "In5.Cu" signal)
		(14 "In6.Cu" power "In6.VCC")
		(2 "B.Cu" signal)
		(9 "F.Adhes" user "F.Adhesive")
		(11 "B.Adhes" user "B.Adhesive")
		(13 "F.Paste" user)
		(15 "B.Paste" user)
		(5 "F.SilkS" user "F.Silkscreen")
		(7 "B.SilkS" user "B.Silkscreen")
		(1 "F.Mask" user)
		(3 "B.Mask" user)
		(17 "Dwgs.User" user "User.Drawings")
		(19 "Cmts.User" user "User.Comments")
		(21 "Eco1.User" user "User.Eco1")
		(23 "Eco2.User" user "User.Eco2")
		(25 "Edge.Cuts" user)
		(27 "Margin" user)
		(31 "F.CrtYd" user "F.Courtyard")
		(29 "B.CrtYd" user "B.Courtyard")
		(35 "F.Fab" user)
		(33 "B.Fab" user)
	)
	(footprint "antmicro-footprints:USON-14_3.5X1.3X0.5mm_P0.5mm"
		(layer "B.Cu")
		(at 208.484328 70.418008 90)
		(property "Reference" "D7"
			(at -0.781992 -1.184328 270)
			(layer "B.SilkS")
			(effects
				(font
					(size 0.7 0.7)
					(thickness 0.15)
				)
				(justify right bottom mirror)
			)
		)
		(property "Value" "TPD6E05U06RVZR"
			(at 0 -2.2 270)
			(layer "B.Fab")
			(effects
				(font
					(size 0.7 0.7)
					(thickness 0.15)
				)
				(justify left bottom mirror)
			)
		)
		(property "Author" "Antmicro"
			(at 278.902336 -138.06632 0)
			(layer "B.Fab")
			(hide yes)
			(effects
				(font
					(size 1 1)
					(thickness 0.15)
				)
				(justify mirror)
			)
		)
		(property "License" "Apache-2.0"
			(at 278.902336 -138.06632 0)
			(layer "B.Fab")
			(hide yes)
			(effects
				(font
					(size 1 1)
					(thickness 0.15)
				)
				(justify mirror)
			)
		)
		(property "MPN" "TPD6E05U06RVZR"
			(at 278.902336 -138.06632 0)
			(layer "B.Fab")
			(hide yes)
			(effects
				(font
					(size 1 1)
					(thickness 0.15)
				)
				(justify mirror)
			)
		)
		(property "Manufacturer" "Texas Instruments"
			(at 278.902336 -138.06632 0)
			(layer "B.Fab")
			(hide yes)
			(effects
				(font
					(size 1 1)
					(thickness 0.15)
				)
				(justify mirror)
			)
		)
		(sheetname "Config SPI flash")
		(sheetfile "config-spi.kicad_sch")
		(attr smd)
		(fp_line
			(start 1.85 -0.96)
			(end -1.59 -0.96)
			(stroke
				(width 0.15)
				(type solid)
			)
			(layer "B.SilkS")
		)
		(fp_line
			(start -1.59 -0.96)
			(end -1.86 -0.69)
			(stroke
				(width 0.15)
				(type solid)
			)
			(layer "B.SilkS")
		)
		(fp_line
			(start -1.86 -0.69)
			(end -1.86 0.96)
			(stroke
				(width 0.15)
				(type solid)
			)
			(layer "B.SilkS")
		)
		(fp_line
			(start 1.85 0.96)
			(end 1.85 -0.96)
			(stroke
				(width 0.15)
				(type solid)
			)
			(layer "B.SilkS")
		)
		(fp_line
			(start -1.86 0.96)
			(end 1.85 0.96)
			(stroke
				(width 0.15)
				(type solid)
			)
			(layer "B.SilkS")
		)
		(fp_circle
			(center -1.86 -0.98)
			(end -1.81 -0.98)
			(stroke
				(width 0.15)
				(type solid)
			)
			(fill no)
			(layer "B.SilkS")
		)
		(fp_rect
			(start -2 1.125)
			(end 2 -1.125)
			(stroke
				(width 0.05)
				(type solid)
			)
			(fill no)
			(layer "B.CrtYd")
		)
		(fp_line
			(start 1.85 -0.96)
			(end 1.85 0.96)
			(stroke
				(width 0.15)
				(type solid)
			)
			(layer "B.Fab")
		)
		(fp_line
			(start -1.58 -0.96)
			(end 1.85 -0.96)
			(stroke
				(width 0.15)
				(type solid)
			)
			(layer "B.Fab")
		)
		(fp_line
			(start -1.845 -0.705)
			(end -1.595 -0.955)
			(stroke
				(width 0.15)
				(type solid)
			)
			(layer "B.Fab")
		)
		(fp_line
			(start 1.85 0.96)
			(end -1.86 0.96)
			(stroke
				(width 0.15)
				(type solid)
			)
			(layer "B.Fab")
		)
		(fp_line
			(start -1.86 0.96)
			(end -1.86 -0.69)
			(stroke
				(width 0.15)
				(type solid)
			)
			(layer "B.Fab")
		)
		(pad "1" smd roundrect
			(at -1.5 -0.623 90)
			(size 0.2 0.5)
			(layers "B.Cu" "B.Mask" "B.Paste")
			(roundrect_rratio 0.25)
			(net 9 "TMS_JTAG")
			(pinfunction "D1+")
			(pintype "passive")
		)
		(pad "2" smd roundrect
			(at -1 -0.623 90)
			(size 0.2 0.5)
			(layers "B.Cu" "B.Mask" "B.Paste")
			(roundrect_rratio 0.25)
			(net 8 "TCK_JTAG")
			(pinfunction "D1-")
			(pintype "passive")
		)
		(pad "3" smd roundrect
			(at -0.5 -0.623 90)
			(size 0.2 0.5)
			(layers "B.Cu" "B.Mask" "B.Paste")
			(roundrect_rratio 0.25)
			(net 64 "unconnected-(D7-D2+-Pad12)")
			(pinfunction "D2+")
			(pintype "passive+no_connect")
		)
		(pad "4" smd roundrect
			(at 0 -0.623 90)
			(size 0.2 0.5)
			(layers "B.Cu" "B.Mask" "B.Paste")
			(roundrect_rratio 0.25)
			(net 65 "unconnected-(D7-D2--Pad11)")
			(pinfunction "D2-")
			(pintype "passive+no_connect")
		)
		(pad "5" smd roundrect
			(at 0.498 -0.623 90)
			(size 0.2 0.5)
			(layers "B.Cu" "B.Mask" "B.Paste")
			(roundrect_rratio 0.25)
			(net 5 "GND")
			(pinfunction "GND")
			(pintype "power_in")
		)
		(pad "6" smd roundrect
			(at 0.998 -0.623 90)
			(size 0.2 0.5)
			(layers "B.Cu" "B.Mask" "B.Paste")
			(roundrect_rratio 0.25)
			(net 11 "TDO_JTAG")
			(pinfunction "D3+")
			(pintype "passive")
		)
		(pad "7" smd roundrect
			(at 1.499 -0.623 90)
			(size 0.2 0.5)
			(layers "B.Cu" "B.Mask" "B.Paste")
			(roundrect_rratio 0.25)
			(net 10 "TDI_JTAG")
			(pinfunction "D3-")
			(pintype "passive")
		)
		(pad "8" smd roundrect
			(at 1.499 0.625 90)
			(size 0.2 0.5)
			(layers "B.Cu" "B.Mask" "B.Paste")
			(roundrect_rratio 0.25)
			(net 10 "TDI_JTAG")
			(pinfunction "D3-")
			(pintype "passive")
		)
		(pad "9" smd roundrect
			(at 0.998 0.625 90)
			(size 0.2 0.5)
			(layers "B.Cu" "B.Mask" "B.Paste")
			(roundrect_rratio 0.25)
			(net 11 "TDO_JTAG")
			(pinfunction "D3+")
			(pintype "passive")
		)
		(pad "10" smd roundrect
			(at 0.498 0.625 90)
			(size 0.2 0.5)
			(layers "B.Cu" "B.Mask" "B.Paste")
			(roundrect_rratio 0.25)
			(net 5 "GND")
			(pinfunction "GND")
			(pintype "passive")
		)
		(pad "11" smd roundrect
			(at 0 0.625 90)
			(size 0.2 0.5)
			(layers "B.Cu" "B.Mask" "B.Paste")
			(roundrect_rratio 0.25)
			(net 65 "unconnected-(D7-D2--Pad11)")
			(pinfunction "D2-")
			(pintype "passive+no_connect")
		)
		(pad "12" smd roundrect
			(at -0.5 0.625 90)
			(size 0.2 0.5)
			(layers "B.Cu" "B.Mask" "B.Paste")
			(roundrect_rratio 0.25)
			(net 64 "unconnected-(D7-D2+-Pad12)")
			(pinfunction "D2+")
			(pintype "passive+no_connect")
		)
		(pad "13" smd roundrect
			(at -1 0.625 90)
			(size 0.2 0.5)
			(layers "B.Cu" "B.Mask" "B.Paste")
			(roundrect_rratio 0.25)
			(net 8 "TCK_JTAG")
			(pinfunction "D1-")
			(pintype "passive")
		)
		(pad "14" smd roundrect
			(at -1.5 0.625 90)
			(size 0.2 0.5)
			(layers "B.Cu" "B.Mask" "B.Paste")
			(roundrect_rratio 0.25)
			(net 9 "TMS_JTAG")
			(pinfunction "D1+")
			(pintype "passive")
		)
	)
	(footprint "antmicro-footprints:R_0402_1005Metric"
		(layer "B.Cu")
		(at 180.1885 118.285757)
		(descr "Resistor SMD 0402")
		(tags "resistor SMD 0402")
		(property "Reference" "R54"
			(at -0.7885 0.414243 180)
			(layer "B.SilkS")
			(effects
				(font
					(size 0.7 0.7)
					(thickness 0.15)
				)
				(justify left bottom mirror)
			)
		)
		(property "Value" "R_100R_0402"
			(at 0 -1.4 180)
			(layer "B.Fab")
			(effects
				(font
					(size 0.7 0.7)
					(thickness 0.15)
				)
				(justify left bottom mirror)
			)
		)
		(property "Description" "100R resistor in 0402 package with 1% tolerance"
			(at 0 0 0)
			(layer "F.Fab")
			(hide yes)
			(effects
				(font
					(size 1.27 1.27)
					(thickness 0.15)
				)
			)
		)
		(property "Author" "Antmicro"
			(at 0 0 0)
			(layer "B.Fab")
			(hide yes)
			(effects
				(font
					(size 1 1)
					(thickness 0.15)
				)
				(justify mirror)
			)
		)
		(property "License" "Apache-2.0"
			(at 0 0 0)
			(layer "B.Fab")
			(hide yes)
			(effects
				(font
					(size 1 1)
					(thickness 0.15)
				)
				(justify mirror)
			)
		)
		(property "MPN" "CR0402-FX-1000GLF"
			(at 0 0 0)
			(layer "B.Fab")
			(hide yes)
			(effects
				(font
					(size 1 1)
					(thickness 0.15)
				)
				(justify mirror)
			)
		)
		(property "Manufacturer" "Bourns"
			(at 0 0 0)
			(layer "B.Fab")
			(hide yes)
			(effects
				(font
					(size 1 1)
					(thickness 0.15)
				)
				(justify mirror)
			)
		)
		(property "Tolerance" "1%"
			(at 0 0 0)
			(layer "B.Fab")
			(hide yes)
			(effects
				(font
					(size 1 1)
					(thickness 0.15)
				)
				(justify mirror)
			)
		)
		(property "Val" "100R"
			(at 0 0 0)
			(layer "B.Fab")
			(hide yes)
			(effects
				(font
					(size 1 1)
					(thickness 0.15)
				)
				(justify mirror)
			)
		)
		(sheetname "Config SPI flash")
		(sheetfile "config-spi.kicad_sch")
		(attr exclude_from_pos_files exclude_from_bom dnp)
		(fp_rect
			(start -0.93 0.47)
			(end 0.93 -0.47)
			(stroke
				(width 0.05)
				(type solid)
			)
			(fill no)
			(layer "B.CrtYd")
		)
		(fp_rect
			(start -0.5 0.25)
			(end 0.5 -0.25)
			(stroke
				(width 0.15)
				(type solid)
			)
			(fill no)
			(layer "B.Fab")
		)
		(pad "1" smd roundrect
			(at -0.485 0)
			(size 0.59 0.64)
			(layers "B.Cu" "B.Mask" "B.Paste")
			(roundrect_rratio 0.25)
			(net 459 "3V3_SYS")
			(pintype "passive")
		)
		(pad "2" smd roundrect
			(at 0.485 0)
			(size 0.59 0.64)
			(layers "B.Cu" "B.Mask" "B.Paste")
			(roundrect_rratio 0.25)
			(net 213 "CCLK")
			(pintype "passive")
		)
	)
	(footprint "antmicro-footprints:R_0402_1005Metric"
		(layer "B.Cu")
		(at 180.1885 119.555757 180)
		(descr "Resistor SMD 0402")
		(tags "resistor SMD 0402")
		(property "Reference" "R55"
			(at 0.7885 -0.444243 0)
			(layer "B.SilkS")
			(effects
				(font
					(size 0.7 0.7)
					(thickness 0.15)
				)
				(justify left bottom mirror)
			)
		)
		(property "Value" "R_100R_0402"
			(at 0 -1.4 0)
			(layer "B.Fab")
			(effects
				(font
					(size 0.7 0.7)
					(thickness 0.15)
				)
				(justify left bottom mirror)
			)
		)
		(property "Description" "100R resistor in 0402 package with 1% tolerance"
			(at 0 0 180)
			(layer "F.Fab")
			(hide yes)
			(effects
				(font
					(size 1.27 1.27)
					(thickness 0.15)
				)
			)
		)
		(property "Author" "Antmicro"
			(at 360.377 239.111514 0)
			(layer "B.Fab")
			(hide yes)
			(effects
				(font
					(size 1 1)
					(thickness 0.15)
				)
				(justify mirror)
			)
		)
		(property "License" "Apache-2.0"
			(at 360.377 239.111514 0)
			(layer "B.Fab")
			(hide yes)
			(effects
				(font
					(size 1 1)
					(thickness 0.15)
				)
				(justify mirror)
			)
		)
		(property "MPN" "CR0402-FX-1000GLF"
			(at 360.377 239.111514 0)
			(layer "B.Fab")
			(hide yes)
			(effects
				(font
					(size 1 1)
					(thickness 0.15)
				)
				(justify mirror)
			)
		)
		(property "Manufacturer" "Bourns"
			(at 360.377 239.111514 0)
			(layer "B.Fab")
			(hide yes)
			(effects
				(font
					(size 1 1)
					(thickness 0.15)
				)
				(justify mirror)
			)
		)
		(property "Tolerance" "1%"
			(at 360.377 239.111514 0)
			(layer "B.Fab")
			(hide yes)
			(effects
				(font
					(size 1 1)
					(thickness 0.15)
				)
				(justify mirror)
			)
		)
		(property "Val" "100R"
			(at 360.377 239.111514 0)
			(layer "B.Fab")
			(hide yes)
			(effects
				(font
					(size 1 1)
					(thickness 0.15)
				)
				(justify mirror)
			)
		)
		(sheetname "Config SPI flash")
		(sheetfile "config-spi.kicad_sch")
		(attr exclude_from_pos_files exclude_from_bom dnp)
		(fp_rect
			(start -0.93 0.47)
			(end 0.93 -0.47)
			(stroke
				(width 0.05)
				(type solid)
			)
			(fill no)
			(layer "B.CrtYd")
		)
		(fp_rect
			(start -0.5 0.25)
			(end 0.5 -0.25)
			(stroke
				(width 0.15)
				(type solid)
			)
			(fill no)
			(layer "B.Fab")
		)
		(pad "1" smd roundrect
			(at -0.485 0 180)
			(size 0.59 0.64)
			(layers "B.Cu" "B.Mask" "B.Paste")
			(roundrect_rratio 0.25)
			(net 213 "CCLK")
			(pintype "passive")
		)
		(pad "2" smd roundrect
			(at 0.485 0 180)
			(size 0.59 0.64)
			(layers "B.Cu" "B.Mask" "B.Paste")
			(roundrect_rratio 0.25)
			(net 5 "GND")
			(pintype "passive")
		)
	)
	(footprint "antmicro-footprints:C_0603_1608Metric"
		(layer "B.Cu")
		(at 159.536328 92.997157 180)
		(descr "Capacitor SMD 0603")
		(tags "capacitor 0603")
		(property "Reference" "C31"
			(at 1.036328 -0.402843 0)
			(layer "B.SilkS")
			(effects
				(font
					(size 0.7 0.7)
					(thickness 0.15)
				)
				(justify left bottom mirror)
			)
		)
		(property "Value" "C_47u_0603"
			(at 0 -1.6 0)
			(layer "B.Fab")
			(effects
				(font
					(size 0.7 0.7)
					(thickness 0.15)
				)
				(justify left bottom mirror)
			)
		)
		(property "Description" " "
			(at 0 0 180)
			(layer "F.Fab")
			(hide yes)
			(effects
				(font
					(size 1.27 1.27)
					(thickness 0.15)
				)
			)
		)
		(property "Author" "Antmicro"
			(at 319.072656 185.994314 0)
			(layer "B.Fab")
			(hide yes)
			(effects
				(font
					(size 1 1)
					(thickness 0.15)
				)
				(justify mirror)
			)
		)
		(property "Dielectric" ""
			(at 319.072656 185.994314 0)
			(layer "B.Fab")
			(hide yes)
			(effects
				(font
					(size 1 1)
					(thickness 0.15)
				)
				(justify mirror)
			)
		)
		(property "License" "Apache-2.0"
			(at 319.072656 185.994314 0)
			(layer "B.Fab")
			(hide yes)
			(effects
				(font
					(size 1 1)
					(thickness 0.15)
				)
				(justify mirror)
			)
		)
		(property "MPN" "GRM188R60J476ME15D"
			(at 319.072656 185.994314 0)
			(layer "B.Fab")
			(hide yes)
			(effects
				(font
					(size 1 1)
					(thickness 0.15)
				)
				(justify mirror)
			)
		)
		(property "Manufacturer" "Murata"
			(at 319.072656 185.994314 0)
			(layer "B.Fab")
			(hide yes)
			(effects
				(font
					(size 1 1)
					(thickness 0.15)
				)
				(justify mirror)
			)
		)
		(property "Val" "47u"
			(at 319.072656 185.994314 0)
			(layer "B.Fab")
			(hide yes)
			(effects
				(font
					(size 1 1)
					(thickness 0.15)
				)
				(justify mirror)
			)
		)
		(property "Voltage" ""
			(at 319.072656 185.994314 0)
			(layer "B.Fab")
			(hide yes)
			(effects
				(font
					(size 1 1)
					(thickness 0.15)
				)
				(justify mirror)
			)
		)
		(sheetname "FPGA power")
		(sheetfile "fpga-power.kicad_sch")
		(attr smd)
		(fp_line
			(start -0.3 0.3)
			(end 0.3 0.3)
			(stroke
				(width 0.15)
				(type solid)
			)
			(layer "B.SilkS")
		)
		(fp_line
			(start -0.3 -0.3)
			(end 0.3 -0.3)
			(stroke
				(width 0.15)
				(type solid)
			)
			(layer "B.SilkS")
		)
		(fp_rect
			(start -1.24 0.7)
			(end 1.24 -0.7)
			(stroke
				(width 0.05)
				(type solid)
			)
			(fill no)
			(layer "B.CrtYd")
		)
		(fp_rect
			(start -0.8 0.4)
			(end 0.8 -0.4)
			(stroke
				(width 0.15)
				(type solid)
			)
			(fill no)
			(layer "B.Fab")
		)
		(pad "1" smd roundrect
			(at -0.7 0 180)
			(size 0.6 0.8)
			(layers "B.Cu" "B.Mask" "B.Paste")
			(roundrect_rratio 0.2)
			(net 66 "VDDQ")
			(pintype "passive")
		)
		(pad "2" smd roundrect
			(at 0.7 0 180)
			(size 0.6 0.8)
			(layers "B.Cu" "B.Mask" "B.Paste")
			(roundrect_rratio 0.2)
			(net 5 "GND")
			(pintype "passive")
		)
	)
	(footprint "antmicro-footprints:C_0603_1608Metric"
		(layer "B.Cu")
		(at 173.036328 89.647157 90)
		(descr "Capacitor SMD 0603")
		(tags "capacitor 0603")
		(property "Reference" "C23"
			(at 3.147157 0.463672 270)
			(layer "B.SilkS")
			(effects
				(font
					(size 0.7 0.7)
					(thickness 0.15)
				)
				(justify left bottom mirror)
			)
		)
		(property "Value" "C_47u_0603"
			(at 0 -1.6 270)
			(layer "B.Fab")
			(effects
				(font
					(size 0.7 0.7)
					(thickness 0.15)
				)
				(justify left bottom mirror)
			)
		)
		(property "Description" " "
			(at 0 0 90)
			(layer "F.Fab")
			(hide yes)
			(effects
				(font
					(size 1.27 1.27)
					(thickness 0.15)
				)
			)
		)
		(property "Author" "Antmicro"
			(at 262.683485 -83.389171 0)
			(layer "B.Fab")
			(hide yes)
			(effects
				(font
					(size 1 1)
					(thickness 0.15)
				)
				(justify mirror)
			)
		)
		(property "Dielectric" ""
			(at 262.683485 -83.389171 0)
			(layer "B.Fab")
			(hide yes)
			(effects
				(font
					(size 1 1)
					(thickness 0.15)
				)
				(justify mirror)
			)
		)
		(property "License" "Apache-2.0"
			(at 262.683485 -83.389171 0)
			(layer "B.Fab")
			(hide yes)
			(effects
				(font
					(size 1 1)
					(thickness 0.15)
				)
				(justify mirror)
			)
		)
		(property "MPN" "GRM188R60J476ME15D"
			(at 262.683485 -83.389171 0)
			(layer "B.Fab")
			(hide yes)
			(effects
				(font
					(size 1 1)
					(thickness 0.15)
				)
				(justify mirror)
			)
		)
		(property "Manufacturer" "Murata"
			(at 262.683485 -83.389171 0)
			(layer "B.Fab")
			(hide yes)
			(effects
				(font
					(size 1 1)
					(thickness 0.15)
				)
				(justify mirror)
			)
		)
		(property "Val" "47u"
			(at 262.683485 -83.389171 0)
			(layer "B.Fab")
			(hide yes)
			(effects
				(font
					(size 1 1)
					(thickness 0.15)
				)
				(justify mirror)
			)
		)
		(property "Voltage" ""
			(at 262.683485 -83.389171 0)
			(layer "B.Fab")
			(hide yes)
			(effects
				(font
					(size 1 1)
					(thickness 0.15)
				)
				(justify mirror)
			)
		)
		(sheetname "FPGA power")
		(sheetfile "fpga-power.kicad_sch")
		(attr smd)
		(fp_line
			(start -0.3 -0.3)
			(end 0.3 -0.3)
			(stroke
				(width 0.15)
				(type solid)
			)
			(layer "B.SilkS")
		)
		(fp_line
			(start -0.3 0.3)
			(end 0.3 0.3)
			(stroke
				(width 0.15)
				(type solid)
			)
			(layer "B.SilkS")
		)
		(fp_rect
			(start -1.24 0.7)
			(end 1.24 -0.7)
			(stroke
				(width 0.05)
				(type solid)
			)
			(fill no)
			(layer "B.CrtYd")
		)
		(fp_rect
			(start -0.8 0.4)
			(end 0.8 -0.4)
			(stroke
				(width 0.15)
				(type solid)
			)
			(fill no)
			(layer "B.Fab")
		)
		(pad "1" smd roundrect
			(at -0.7 0 90)
			(size 0.6 0.8)
			(layers "B.Cu" "B.Mask" "B.Paste")
			(roundrect_rratio 0.2)
			(net 459 "3V3_SYS")
			(pintype "passive")
		)
		(pad "2" smd roundrect
			(at 0.7 0 90)
			(size 0.6 0.8)
			(layers "B.Cu" "B.Mask" "B.Paste")
			(roundrect_rratio 0.2)
			(net 5 "GND")
			(pintype "passive")
		)
	)
)
